(kicad_pcb
	(version 20260206)
	(generator "pcbnew")
	(generator_version "10.0")
	(general
		(thickness 1.6)
		(legacy_teardrops no)
	)
	(paper "A4")
	(title_block
		(title "01162023_DA0F0TEBIF0_F0T_Expander_BD_F_brd_V02_OCP.brd")
		(comment 1 "Grand Teton / footprints 9433-9441 of 9728")
	)
	(layers
		(0 "F.Cu" signal "TOP")
		(4 "In1.Cu" signal "GND")
		(6 "In2.Cu" signal "VCC")
		(8 "In3.Cu" signal "VCC1")
		(10 "In4.Cu" signal "GND1")
		(12 "In5.Cu" signal "IN1")
		(14 "In6.Cu" signal "GND2")
		(16 "In7.Cu" signal "IN2")
		(18 "In8.Cu" signal "GND3")
		(20 "In9.Cu" signal "IN3")
		(22 "In10.Cu" signal "GND4")
		(24 "In11.Cu" signal "IN4")
		(26 "In12.Cu" signal "GND5")
		(28 "In13.Cu" signal "IN5")
		(30 "In14.Cu" signal "GND6")
		(32 "In15.Cu" signal "IN6")
		(34 "In16.Cu" signal "GND7")
		(2 "B.Cu" signal "BOTTOM")
		(9 "F.Adhes" user "F.Adhesive")
		(11 "B.Adhes" user "B.Adhesive")
		(13 "F.Paste" user "Package Geometry/Pastemask Top")
		(15 "B.Paste" user "Package Geometry/Pastemask Bottom")
		(5 "F.SilkS" user "Ref Des/Silkscreen Top")
		(7 "B.SilkS" user "Ref Des/Silkscreen Bottom")
		(1 "F.Mask" user "Board Geometry/Soldermask Top")
		(3 "B.Mask" user "Board Geometry/Soldermask Bottom")
		(17 "Dwgs.User" user "User.Drawings")
		(19 "Cmts.User" user "User.Comments")
		(21 "Eco1.User" user "User.Eco1")
		(23 "Eco2.User" user "User.Eco2")
		(25 "Edge.Cuts" user "Board Geometry/Outline")
		(27 "Margin" user)
		(31 "F.CrtYd" user "Package Geometry/Place Bound Top")
		(29 "B.CrtYd" user "Package Geometry/Place Bound Bottom")
		(35 "F.Fab" user "Ref Des/Assembly Top")
		(33 "B.Fab" user "Ref Des/Assembly Bottom")
	)
	(footprint ""
		(layer "B.Cu")
		(at 62.499748 -290.199826 90)
		(property "Reference" "C1240"
			(at 0 0 90)
			(layer "B.SilkS")
			(hide yes)
			(effects
				(font
					(size 1.27 1.27)
				)
				(justify mirror)
			)
		)
		(property "Value" ""
			(at 0 0 90)
			(layer "B.Fab")
			(effects
				(font
					(size 1.27 1.27)
				)
				(justify mirror)
			)
		)
		(duplicate_pad_numbers_are_jumpers no)
		(fp_line
			(start 0.299974 -0.150114)
			(end -0.299974 -0.150114)
			(stroke
				(width 0.1)
				(type default)
			)
			(layer "B.Fab")
		)
		(fp_line
			(start -0.299974 -0.150114)
			(end -0.299974 0.150114)
			(stroke
				(width 0.1)
				(type default)
			)
			(layer "B.Fab")
		)
		(fp_line
			(start 0.299974 0.150114)
			(end 0.299974 -0.150114)
			(stroke
				(width 0.1)
				(type default)
			)
			(layer "B.Fab")
		)
		(fp_line
			(start -0.299974 0.150114)
			(end 0.299974 0.150114)
			(stroke
				(width 0.1)
				(type default)
			)
			(layer "B.Fab")
		)
		(pad "1" smd rect
			(at 0.2667 0 270)
			(size 0.3048 0.381)
			(layers "B.Cu" "B.Mask" "B.Paste")
			(net "P0V8_SERDES_VDDA_PEX0")
		)
		(pad "2" smd rect
			(at -0.2667 0 270)
			(size 0.3048 0.381)
			(layers "B.Cu" "B.Mask" "B.Paste")
			(net "GND")
		)
	)
	(footprint ""
		(layer "B.Cu")
		(at 127.034544 -303.649634 -90)
		(property "Reference" "PC117"
			(at 0 0 90)
			(layer "B.SilkS")
			(hide yes)
			(effects
				(font
					(size 1.27 1.27)
				)
				(justify mirror)
			)
		)
		(property "Value" ""
			(at 0 0 90)
			(layer "B.Fab")
			(effects
				(font
					(size 1.27 1.27)
				)
				(justify mirror)
			)
		)
		(duplicate_pad_numbers_are_jumpers no)
		(fp_line
			(start -1.524 0.762)
			(end 1.524 0.762)
			(stroke
				(width 0.1524)
				(type default)
			)
			(layer "B.SilkS")
		)
		(fp_line
			(start 1.524 0.762)
			(end 1.524 -0.762)
			(stroke
				(width 0.1524)
				(type default)
			)
			(layer "B.SilkS")
		)
		(fp_line
			(start -1.524 -0.762)
			(end -1.524 0.762)
			(stroke
				(width 0.1524)
				(type default)
			)
			(layer "B.SilkS")
		)
		(fp_line
			(start 1.524 -0.762)
			(end -1.524 -0.762)
			(stroke
				(width 0.1524)
				(type default)
			)
			(layer "B.SilkS")
		)
		(fp_line
			(start -1.1049 0.724916)
			(end -1.1049 -0.724916)
			(stroke
				(width 0.1)
				(type default)
			)
			(layer "B.Fab")
		)
		(fp_line
			(start 1.1049 0.724916)
			(end -1.1049 0.724916)
			(stroke
				(width 0.1)
				(type default)
			)
			(layer "B.Fab")
		)
		(fp_line
			(start -1.1049 -0.724916)
			(end 1.1049 -0.724916)
			(stroke
				(width 0.1)
				(type default)
			)
			(layer "B.Fab")
		)
		(fp_line
			(start 1.1049 -0.724916)
			(end 1.1049 0.724916)
			(stroke
				(width 0.1)
				(type default)
			)
			(layer "B.Fab")
		)
		(pad "1" smd rect
			(at 0.889 0 270)
			(size 1.016 1.27)
			(layers "B.Cu" "B.Mask" "B.Paste")
			(net "P0V8_PEX1")
		)
		(pad "2" smd rect
			(at -0.889 0 270)
			(size 1.016 1.27)
			(layers "B.Cu" "B.Mask" "B.Paste")
			(net "GND")
		)
	)
	(footprint ""
		(layer "B.Cu")
		(at 415.549842 -301.599854 -90)
		(property "Reference" "C1950"
			(at 0 0 90)
			(layer "B.SilkS")
			(hide yes)
			(effects
				(font
					(size 1.27 1.27)
				)
				(justify mirror)
			)
		)
		(property "Value" ""
			(at 0 0 90)
			(layer "B.Fab")
			(effects
				(font
					(size 1.27 1.27)
				)
				(justify mirror)
			)
		)
		(duplicate_pad_numbers_are_jumpers no)
		(fp_line
			(start -0.299974 0.150114)
			(end 0.299974 0.150114)
			(stroke
				(width 0.1)
				(type default)
			)
			(layer "B.Fab")
		)
		(fp_line
			(start 0.299974 0.150114)
			(end 0.299974 -0.150114)
			(stroke
				(width 0.1)
				(type default)
			)
			(layer "B.Fab")
		)
		(fp_line
			(start -0.299974 -0.150114)
			(end -0.299974 0.150114)
			(stroke
				(width 0.1)
				(type default)
			)
			(layer "B.Fab")
		)
		(fp_line
			(start 0.299974 -0.150114)
			(end -0.299974 -0.150114)
			(stroke
				(width 0.1)
				(type default)
			)
			(layer "B.Fab")
		)
		(pad "1" smd rect
			(at 0.2667 0 90)
			(size 0.3048 0.381)
			(layers "B.Cu" "B.Mask" "B.Paste")
			(net "P0V8_SERDES_VDDA_PEX3")
		)
		(pad "2" smd rect
			(at -0.2667 0 90)
			(size 0.3048 0.381)
			(layers "B.Cu" "B.Mask" "B.Paste")
			(net "GND")
		)
	)
	(footprint ""
		(layer "B.Cu")
		(at 303.249838 -297.32478 180)
		(property "Reference" "C3258"
			(at 0 0 0)
			(layer "B.SilkS")
			(hide yes)
			(effects
				(font
					(size 1.27 1.27)
				)
				(justify mirror)
			)
		)
		(property "Value" ""
			(at 0 0 0)
			(layer "B.Fab")
			(effects
				(font
					(size 1.27 1.27)
				)
				(justify mirror)
			)
		)
		(duplicate_pad_numbers_are_jumpers no)
		(fp_line
			(start 0.299974 0.150114)
			(end 0.299974 -0.150114)
			(stroke
				(width 0.1)
				(type default)
			)
			(layer "B.Fab")
		)
		(fp_line
			(start 0.299974 -0.150114)
			(end -0.299974 -0.150114)
			(stroke
				(width 0.1)
				(type default)
			)
			(layer "B.Fab")
		)
		(fp_line
			(start -0.299974 0.150114)
			(end 0.299974 0.150114)
			(stroke
				(width 0.1)
				(type default)
			)
			(layer "B.Fab")
		)
		(fp_line
			(start -0.299974 -0.150114)
			(end -0.299974 0.150114)
			(stroke
				(width 0.1)
				(type default)
			)
			(layer "B.Fab")
		)
		(pad "1" smd rect
			(at 0.2667 0)
			(size 0.3048 0.381)
			(layers "B.Cu" "B.Mask" "B.Paste")
			(net "P1V25_PEX2")
		)
		(pad "2" smd rect
			(at -0.2667 0)
			(size 0.3048 0.381)
			(layers "B.Cu" "B.Mask" "B.Paste")
			(net "GND")
		)
	)
	(footprint ""
		(layer "B.Cu")
		(at 297.103038 -202.16114 90)
		(property "Reference" "R1037"
			(at 0 0 90)
			(layer "B.SilkS")
			(hide yes)
			(effects
				(font
					(size 1.27 1.27)
				)
				(justify mirror)
			)
		)
		(property "Value" ""
			(at 0 0 90)
			(layer "B.Fab")
			(effects
				(font
					(size 1.27 1.27)
				)
				(justify mirror)
			)
		)
		(duplicate_pad_numbers_are_jumpers no)
		(fp_line
			(start 0.7874 -0.4064)
			(end -0.7874 -0.4064)
			(stroke
				(width 0.1524)
				(type default)
			)
			(layer "B.SilkS")
		)
		(fp_line
			(start -0.7874 -0.4064)
			(end -0.7874 0.4064)
			(stroke
				(width 0.1524)
				(type default)
			)
			(layer "B.SilkS")
		)
		(fp_line
			(start 0.7874 0.4064)
			(end 0.7874 -0.4064)
			(stroke
				(width 0.1524)
				(type default)
			)
			(layer "B.SilkS")
		)
		(fp_line
			(start -0.7874 0.4064)
			(end 0.7874 0.4064)
			(stroke
				(width 0.1524)
				(type default)
			)
			(layer "B.SilkS")
		)
		(fp_line
			(start 0.67945 -0.305054)
			(end 0.12065 -0.305054)
			(stroke
				(width 0.1)
				(type default)
			)
			(layer "B.Fab")
		)
		(fp_line
			(start 0.12065 -0.305054)
			(end 0.12065 -0.2794)
			(stroke
				(width 0.1)
				(type default)
			)
			(layer "B.Fab")
		)
		(fp_line
			(start -0.12065 -0.3048)
			(end -0.67945 -0.3048)
			(stroke
				(width 0.1)
				(type default)
			)
			(layer "B.Fab")
		)
		(fp_line
			(start -0.67945 -0.3048)
			(end -0.67945 0.3048)
			(stroke
				(width 0.1)
				(type default)
			)
			(layer "B.Fab")
		)
		(fp_line
			(start 0.12065 -0.2794)
			(end -0.12065 -0.2794)
			(stroke
				(width 0.1)
				(type default)
			)
			(layer "B.Fab")
		)
		(fp_line
			(start -0.12065 -0.2794)
			(end -0.12065 -0.3048)
			(stroke
				(width 0.1)
				(type default)
			)
			(layer "B.Fab")
		)
		(fp_line
			(start 0.12065 0.2794)
			(end 0.12065 0.3048)
			(stroke
				(width 0.1)
				(type default)
			)
			(layer "B.Fab")
		)
		(fp_line
			(start -0.120396 0.2794)
			(end 0.12065 0.2794)
			(stroke
				(width 0.1)
				(type default)
			)
			(layer "B.Fab")
		)
		(fp_line
			(start 0.67945 0.3048)
			(end 0.67945 -0.305054)
			(stroke
				(width 0.1)
				(type default)
			)
			(layer "B.Fab")
		)
		(fp_line
			(start 0.12065 0.3048)
			(end 0.67945 0.3048)
			(stroke
				(width 0.1)
				(type default)
			)
			(layer "B.Fab")
		)
		(fp_line
			(start -0.120396 0.3048)
			(end -0.120396 0.2794)
			(stroke
				(width 0.1)
				(type default)
			)
			(layer "B.Fab")
		)
		(fp_line
			(start -0.67945 0.3048)
			(end -0.120396 0.3048)
			(stroke
				(width 0.1)
				(type default)
			)
			(layer "B.Fab")
		)
		(pad "1" smd circle
			(at 0.40005 0 270)
			(size 0 0)
			(layers "B.Cu" "B.Mask" "B.Paste")
			(net "SPI_BIC1_CS0_LS23_N_DIR1")
		)
		(pad "2" smd circle
			(at -0.40005 0 270)
			(size 0 0)
			(layers "B.Cu" "B.Mask" "B.Paste")
			(net "P1V8_PEX")
		)
	)
	(footprint ""
		(layer "B.Cu")
		(at 327.523856 -223.977708 180)
		(property "Reference" "R6415"
			(at 0 0 0)
			(layer "B.SilkS")
			(hide yes)
			(effects
				(font
					(size 1.27 1.27)
				)
				(justify mirror)
			)
		)
		(property "Value" ""
			(at 0 0 0)
			(layer "B.Fab")
			(effects
				(font
					(size 1.27 1.27)
				)
				(justify mirror)
			)
		)
		(duplicate_pad_numbers_are_jumpers no)
		(fp_line
			(start 0.7874 0.4064)
			(end 0.7874 -0.4064)
			(stroke
				(width 0.1524)
				(type default)
			)
			(layer "B.SilkS")
		)
		(fp_line
			(start 0.7874 -0.4064)
			(end -0.7874 -0.4064)
			(stroke
				(width 0.1524)
				(type default)
			)
			(layer "B.SilkS")
		)
		(fp_line
			(start -0.7874 0.4064)
			(end 0.7874 0.4064)
			(stroke
				(width 0.1524)
				(type default)
			)
			(layer "B.SilkS")
		)
		(fp_line
			(start -0.7874 -0.4064)
			(end -0.7874 0.4064)
			(stroke
				(width 0.1524)
				(type default)
			)
			(layer "B.SilkS")
		)
		(fp_line
			(start 0.67945 0.3048)
			(end 0.67945 -0.305054)
			(stroke
				(width 0.1)
				(type default)
			)
			(layer "B.Fab")
		)
		(fp_line
			(start 0.67945 -0.305054)
			(end 0.12065 -0.305054)
			(stroke
				(width 0.1)
				(type default)
			)
			(layer "B.Fab")
		)
		(fp_line
			(start 0.12065 0.3048)
			(end 0.67945 0.3048)
			(stroke
				(width 0.1)
				(type default)
			)
			(layer "B.Fab")
		)
		(fp_line
			(start 0.12065 0.2794)
			(end 0.12065 0.3048)
			(stroke
				(width 0.1)
				(type default)
			)
			(layer "B.Fab")
		)
		(fp_line
			(start 0.12065 -0.2794)
			(end -0.12065 -0.2794)
			(stroke
				(width 0.1)
				(type default)
			)
			(layer "B.Fab")
		)
		(fp_line
			(start 0.12065 -0.305054)
			(end 0.12065 -0.2794)
			(stroke
				(width 0.1)
				(type default)
			)
			(layer "B.Fab")
		)
		(fp_line
			(start -0.120396 0.3048)
			(end -0.120396 0.2794)
			(stroke
				(width 0.1)
				(type default)
			)
			(layer "B.Fab")
		)
		(fp_line
			(start -0.120396 0.2794)
			(end 0.12065 0.2794)
			(stroke
				(width 0.1)
				(type default)
			)
			(layer "B.Fab")
		)
		(fp_line
			(start -0.12065 -0.2794)
			(end -0.12065 -0.3048)
			(stroke
				(width 0.1)
				(type default)
			)
			(layer "B.Fab")
		)
		(fp_line
			(start -0.12065 -0.3048)
			(end -0.67945 -0.3048)
			(stroke
				(width 0.1)
				(type default)
			)
			(layer "B.Fab")
		)
		(fp_line
			(start -0.67945 0.3048)
			(end -0.120396 0.3048)
			(stroke
				(width 0.1)
				(type default)
			)
			(layer "B.Fab")
		)
		(fp_line
			(start -0.67945 -0.3048)
			(end -0.67945 0.3048)
			(stroke
				(width 0.1)
				(type default)
			)
			(layer "B.Fab")
		)
		(pad "1" smd circle
			(at 0.40005 0)
			(size 0 0)
			(layers "B.Cu" "B.Mask" "B.Paste")
			(net "GND")
		)
		(pad "2" smd circle
			(at -0.40005 0)
			(size 0 0)
			(layers "B.Cu" "B.Mask" "B.Paste")
			(net "FM_SYS_THROTTLE")
		)
	)
	(footprint ""
		(layer "B.Cu")
		(at 293.27475 -286.399732 90)
		(property "Reference" "C3304"
			(at 0 0 90)
			(layer "B.SilkS")
			(hide yes)
			(effects
				(font
					(size 1.27 1.27)
				)
				(justify mirror)
			)
		)
		(property "Value" ""
			(at 0 0 90)
			(layer "B.Fab")
			(effects
				(font
					(size 1.27 1.27)
				)
				(justify mirror)
			)
		)
		(duplicate_pad_numbers_are_jumpers no)
		(fp_line
			(start 0.299974 -0.150114)
			(end -0.299974 -0.150114)
			(stroke
				(width 0.1)
				(type default)
			)
			(layer "B.Fab")
		)
		(fp_line
			(start -0.299974 -0.150114)
			(end -0.299974 0.150114)
			(stroke
				(width 0.1)
				(type default)
			)
			(layer "B.Fab")
		)
		(fp_line
			(start 0.299974 0.150114)
			(end 0.299974 -0.150114)
			(stroke
				(width 0.1)
				(type default)
			)
			(layer "B.Fab")
		)
		(fp_line
			(start -0.299974 0.150114)
			(end 0.299974 0.150114)
			(stroke
				(width 0.1)
				(type default)
			)
			(layer "B.Fab")
		)
		(pad "1" smd rect
			(at 0.2667 0 270)
			(size 0.3048 0.381)
			(layers "B.Cu" "B.Mask" "B.Paste")
			(net "P1V25_SERDES_VDDPLL_PEX2")
		)
		(pad "2" smd rect
			(at -0.2667 0 270)
			(size 0.3048 0.381)
			(layers "B.Cu" "B.Mask" "B.Paste")
			(net "GND")
		)
	)
	(footprint ""
		(layer "B.Cu")
		(at 291.84981 -301.599854 -90)
		(property "Reference" "C1728"
			(at 0 0 90)
			(layer "B.SilkS")
			(hide yes)
			(effects
				(font
					(size 1.27 1.27)
				)
				(justify mirror)
			)
		)
		(property "Value" ""
			(at 0 0 90)
			(layer "B.Fab")
			(effects
				(font
					(size 1.27 1.27)
				)
				(justify mirror)
			)
		)
		(duplicate_pad_numbers_are_jumpers no)
		(fp_line
			(start -0.299974 0.150114)
			(end 0.299974 0.150114)
			(stroke
				(width 0.1)
				(type default)
			)
			(layer "B.Fab")
		)
		(fp_line
			(start 0.299974 0.150114)
			(end 0.299974 -0.150114)
			(stroke
				(width 0.1)
				(type default)
			)
			(layer "B.Fab")
		)
		(fp_line
			(start -0.299974 -0.150114)
			(end -0.299974 0.150114)
			(stroke
				(width 0.1)
				(type default)
			)
			(layer "B.Fab")
		)
		(fp_line
			(start 0.299974 -0.150114)
			(end -0.299974 -0.150114)
			(stroke
				(width 0.1)
				(type default)
			)
			(layer "B.Fab")
		)
		(pad "1" smd rect
			(at 0.2667 0 90)
			(size 0.3048 0.381)
			(layers "B.Cu" "B.Mask" "B.Paste")
			(net "P0V8_SERDES_VDDA_PEX2")
		)
		(pad "2" smd rect
			(at -0.2667 0 90)
			(size 0.3048 0.381)
			(layers "B.Cu" "B.Mask" "B.Paste")
			(net "GND")
		)
	)
	(footprint ""
		(layer "B.Cu")
		(at 145.804382 -226.78263 180)
		(property "Reference" "R6165"
			(at 0 0 0)
			(layer "B.SilkS")
			(hide yes)
			(effects
				(font
					(size 1.27 1.27)
				)
				(justify mirror)
			)
		)
		(property "Value" ""
			(at 0 0 0)
			(layer "B.Fab")
			(effects
				(font
					(size 1.27 1.27)
				)
				(justify mirror)
			)
		)
		(duplicate_pad_numbers_are_jumpers no)
		(fp_line
			(start 0.7874 0.4064)
			(end 0.7874 -0.4064)
			(stroke
				(width 0.1524)
				(type default)
			)
			(layer "B.SilkS")
		)
		(fp_line
			(start 0.7874 -0.4064)
			(end -0.7874 -0.4064)
			(stroke
				(width 0.1524)
				(type default)
			)
			(layer "B.SilkS")
		)
		(fp_line
			(start -0.7874 0.4064)
			(end 0.7874 0.4064)
			(stroke
				(width 0.1524)
				(type default)
			)
			(layer "B.SilkS")
		)
		(fp_line
			(start -0.7874 -0.4064)
			(end -0.7874 0.4064)
			(stroke
				(width 0.1524)
				(type default)
			)
			(layer "B.SilkS")
		)
		(fp_line
			(start 0.67945 0.3048)
			(end 0.67945 -0.305054)
			(stroke
				(width 0.1)
				(type default)
			)
			(layer "B.Fab")
		)
		(fp_line
			(start 0.67945 -0.305054)
			(end 0.12065 -0.305054)
			(stroke
				(width 0.1)
				(type default)
			)
			(layer "B.Fab")
		)
		(fp_line
			(start 0.12065 0.3048)
			(end 0.67945 0.3048)
			(stroke
				(width 0.1)
				(type default)
			)
			(layer "B.Fab")
		)
		(fp_line
			(start 0.12065 0.2794)
			(end 0.12065 0.3048)
			(stroke
				(width 0.1)
				(type default)
			)
			(layer "B.Fab")
		)
		(fp_line
			(start 0.12065 -0.2794)
			(end -0.12065 -0.2794)
			(stroke
				(width 0.1)
				(type default)
			)
			(layer "B.Fab")
		)
		(fp_line
			(start 0.12065 -0.305054)
			(end 0.12065 -0.2794)
			(stroke
				(width 0.1)
				(type default)
			)
			(layer "B.Fab")
		)
		(fp_line
			(start -0.120396 0.3048)
			(end -0.120396 0.2794)
			(stroke
				(width 0.1)
				(type default)
			)
			(layer "B.Fab")
		)
		(fp_line
			(start -0.120396 0.2794)
			(end 0.12065 0.2794)
			(stroke
				(width 0.1)
				(type default)
			)
			(layer "B.Fab")
		)
		(fp_line
			(start -0.12065 -0.2794)
			(end -0.12065 -0.3048)
			(stroke
				(width 0.1)
				(type default)
			)
			(layer "B.Fab")
		)
		(fp_line
			(start -0.12065 -0.3048)
			(end -0.67945 -0.3048)
			(stroke
				(width 0.1)
				(type default)
			)
			(layer "B.Fab")
		)
		(fp_line
			(start -0.67945 0.3048)
			(end -0.120396 0.3048)
			(stroke
				(width 0.1)
				(type default)
			)
			(layer "B.Fab")
		)
		(fp_line
			(start -0.67945 -0.3048)
			(end -0.67945 0.3048)
			(stroke
				(width 0.1)
				(type default)
			)
			(layer "B.Fab")
		)
		(pad "1" smd circle
			(at 0.40005 0)
			(size 0 0)
			(layers "B.Cu" "B.Mask" "B.Paste")
			(net "SPI_PEX1_RST_R_N")
		)
		(pad "2" smd circle
			(at -0.40005 0)
			(size 0 0)
			(layers "B.Cu" "B.Mask" "B.Paste")
			(net "SPI_PEX1_RST_N")
		)
	)
)
